FILE_TYPE = CONNECTIVITY;
{Allegro Design Entry HDL 16.6-p007 (v16-6-112F) 10/10/2012}
"PAGE_NUMBER" = 30;
0"NC";
1"P3E_CPU0_PE1_PCH_TXN<15:8>";
2"P3E_CPU0_PE1_SS_TXN<7:0>";
3"P3E_CPU0_PE1_PCH_TXP<15:8>";
4"P3E_CPU0_PE1_SS_TXP<7:0>";
5"P3E_CPU0_PE1_PCH_RXN<15:8>";
6"P3E_CPU0_PE1_SS_RXN<7:0>";
7"P3E_CPU0_PE1_PCH_RXP<15:8>";
8"P3E_CPU0_PE1_SS_RXP<7:0>";
9"P3E_CPU0_PE1_SS_RXN<3>";
10"P3E_CPU0_PE1_SS_RXP<0>";
11"P3E_CPU0_PE1_SS_RXP<1>";
12"P3E_CPU0_PE1_SS_RXP<2>";
13"P3E_CPU0_PE1_SS_RXP<3>";
14"P3E_CPU0_PE1_SS_RXN<0>";
15"P3E_CPU0_PE1_SS_RXN<1>";
16"P3E_CPU0_PE1_SS_RXN<2>";
17"P3E_CPU0_PE1_SS_RXP<4>";
18"P3E_CPU0_PE1_SS_RXP<5>";
19"P3E_CPU0_PE1_SS_RXP<6>";
20"P3E_CPU0_PE1_SS_RXP<7>";
21"P3E_CPU0_PE1_PCH_RXP<8>";
22"P3E_CPU0_PE1_PCH_RXP<9>";
23"P3E_CPU0_PE1_PCH_RXP<10>";
24"P3E_CPU0_PE1_PCH_RXP<11>";
25"P3E_CPU0_PE1_PCH_RXP<12>";
26"P3E_CPU0_PE1_PCH_RXP<13>";
27"P3E_CPU0_PE1_PCH_RXP<14>";
28"P3E_CPU0_PE1_PCH_RXP<15>";
29"P3E_CPU0_PE1_SS_RXN<4>";
30"P3E_CPU0_PE1_SS_RXN<5>";
31"P3E_CPU0_PE1_SS_RXN<6>";
32"P3E_CPU0_PE1_SS_RXN<7>";
33"P3E_CPU0_PE1_PCH_RXN<8>";
34"P3E_CPU0_PE1_PCH_RXN<9>";
35"P3E_CPU0_PE1_PCH_RXN<10>";
36"P3E_CPU0_PE1_PCH_RXN<11>";
37"P3E_CPU0_PE1_PCH_RXN<12>";
38"P3E_CPU0_PE1_PCH_RXN<13>";
39"P3E_CPU0_PE1_PCH_RXN<14>";
40"P3E_CPU0_PE1_PCH_RXN<15>";
41"P3E_CPU0_PE1_SS_TXP<0>";
42"P3E_CPU0_PE1_SS_TXP<1>";
43"P3E_CPU0_PE1_SS_TXP<2>";
44"P3E_CPU0_PE1_SS_TXP<3>";
45"P3E_CPU0_PE1_SS_TXN<0>";
46"P3E_CPU0_PE1_SS_TXN<1>";
47"P3E_CPU0_PE1_SS_TXN<2>";
48"P3E_CPU0_PE1_SS_TXN<3>";
49"P3E_CPU0_PE1_SS_TXP<4>";
50"P3E_CPU0_PE1_SS_TXP<5>";
51"P3E_CPU0_PE1_SS_TXP<6>";
52"P3E_CPU0_PE1_SS_TXP<7>";
53"P3E_CPU0_PE1_PCH_TXP<8>";
54"P3E_CPU0_PE1_PCH_TXP<9>";
55"P3E_CPU0_PE1_PCH_TXP<10>";
56"P3E_CPU0_PE1_PCH_TXP<11>";
57"P3E_CPU0_PE1_PCH_TXP<12>";
58"P3E_CPU0_PE1_PCH_TXP<13>";
59"P3E_CPU0_PE1_PCH_TXP<14>";
60"P3E_CPU0_PE1_PCH_TXP<15>";
61"P3E_CPU0_PE1_SS_TXN<4>";
62"P3E_CPU0_PE1_SS_TXN<5>";
63"P3E_CPU0_PE1_SS_TXN<6>";
64"P3E_CPU0_PE1_SS_TXN<7>";
65"P3E_CPU0_PE1_PCH_TXN<8>";
66"P3E_CPU0_PE1_PCH_TXN<9>";
67"P3E_CPU0_PE1_PCH_TXN<10>";
68"P3E_CPU0_PE1_PCH_TXN<11>";
69"P3E_CPU0_PE1_PCH_TXN<12>";
70"P3E_CPU0_PE1_PCH_TXN<13>";
71"P3E_CPU0_PE1_PCH_TXN<14>";
72"P3E_CPU0_PE1_PCH_TXN<15>";
%"TAP"
"1","(-5825,1900)","2","mstr_standard","I1";
;
HDL_TAP"TRUE"
BODY_TYPE"PLUMBING"
CDS_LIB"mstr_standard";
"B \NAC \NWC"8;
"S \NAC"
BN"1"11;
%"TAP"
"1","(-5825,2500)","2","mstr_standard","I10";
;
HDL_TAP"TRUE"
BODY_TYPE"PLUMBING"
CDS_LIB"mstr_standard";
"B \NAC \NWC"8;
"S \NAC"
BN"7"20;
%"TAP"
"1","(-5825,2850)","2","mstr_standard","I11";
;
HDL_TAP"TRUE"
BODY_TYPE"PLUMBING"
CDS_LIB"mstr_standard";
"B \NAC \NWC"7;
"S \NAC"
BN"8"21;
%"TAP"
"1","(-5825,2900)","2","mstr_standard","I12";
;
HDL_TAP"TRUE"
BODY_TYPE"PLUMBING"
CDS_LIB"mstr_standard";
"B \NAC \NWC"7;
"S \NAC"
BN"9"22;
%"TAP"
"1","(-5825,2950)","2","mstr_standard","I13";
;
HDL_TAP"TRUE"
BODY_TYPE"PLUMBING"
CDS_LIB"mstr_standard";
"B \NAC \NWC"7;
"S \NAC"
BN"10"23;
%"TAP"
"1","(-5825,3000)","2","mstr_standard","I14";
;
HDL_TAP"TRUE"
BODY_TYPE"PLUMBING"
CDS_LIB"mstr_standard";
"B \NAC \NWC"7;
"S \NAC"
BN"11"24;
%"TAP"
"1","(-5825,3350)","2","mstr_standard","I15";
;
HDL_TAP"TRUE"
BODY_TYPE"PLUMBING"
CDS_LIB"mstr_standard";
"B \NAC \NWC"7;
"S \NAC"
BN"12"25;
%"TAP"
"1","(-5825,3400)","2","mstr_standard","I16";
;
HDL_TAP"TRUE"
BODY_TYPE"PLUMBING"
CDS_LIB"mstr_standard";
"B \NAC \NWC"7;
"S \NAC"
BN"13"26;
%"TAP"
"1","(-5825,3500)","2","mstr_standard","I17";
;
HDL_TAP"TRUE"
BODY_TYPE"PLUMBING"
CDS_LIB"mstr_standard";
"B \NAC \NWC"7;
"S \NAC"
BN"15"28;
%"TAP"
"1","(-5825,3450)","2","mstr_standard","I18";
;
HDL_TAP"TRUE"
BODY_TYPE"PLUMBING"
CDS_LIB"mstr_standard";
"B \NAC \NWC"7;
"S \NAC"
BN"14"27;
%"TAP"
"1","(-5550,1650)","2","mstr_standard","I19";
;
HDL_TAP"TRUE"
BODY_TYPE"PLUMBING"
CDS_LIB"mstr_standard";
"B \NAC \NWC"6;
"S \NAC"
BN"1"15;
%"TAP"
"1","(-5825,1850)","2","mstr_standard","I2";
;
HDL_TAP"TRUE"
BODY_TYPE"PLUMBING"
CDS_LIB"mstr_standard";
"B \NAC \NWC"8;
"S \NAC"
BN"0"10;
%"TAP"
"1","(-5550,1600)","2","mstr_standard","I20";
;
HDL_TAP"TRUE"
BODY_TYPE"PLUMBING"
CDS_LIB"mstr_standard";
"B \NAC \NWC"6;
"S \NAC"
BN"0"14;
%"TAP"
"1","(-5550,1750)","2","mstr_standard","I21";
;
HDL_TAP"TRUE"
BODY_TYPE"PLUMBING"
CDS_LIB"mstr_standard";
"B \NAC \NWC"6;
"S \NAC"
BN"3"9;
%"TAP"
"1","(-5550,1700)","2","mstr_standard","I22";
;
HDL_TAP"TRUE"
BODY_TYPE"PLUMBING"
CDS_LIB"mstr_standard";
"B \NAC \NWC"6;
"S \NAC"
BN"2"16;
%"TAP"
"1","(-5550,2150)","2","mstr_standard","I24";
;
HDL_TAP"TRUE"
BODY_TYPE"PLUMBING"
CDS_LIB"mstr_standard";
"B \NAC \NWC"6;
"S \NAC"
BN"5"30;
%"TAP"
"1","(-5550,2200)","2","mstr_standard","I25";
;
HDL_TAP"TRUE"
BODY_TYPE"PLUMBING"
CDS_LIB"mstr_standard";
"B \NAC \NWC"6;
"S \NAC"
BN"6"31;
%"TAP"
"1","(-5550,2100)","2","mstr_standard","I26";
;
HDL_TAP"TRUE"
BODY_TYPE"PLUMBING"
CDS_LIB"mstr_standard";
"B \NAC \NWC"6;
"S \NAC"
BN"4"29;
%"TAP"
"1","(-5550,2250)","2","mstr_standard","I27";
;
HDL_TAP"TRUE"
BODY_TYPE"PLUMBING"
CDS_LIB"mstr_standard";
"B \NAC \NWC"6;
"S \NAC"
BN"7"32;
%"TAP"
"1","(-5550,2600)","2","mstr_standard","I28";
;
HDL_TAP"TRUE"
BODY_TYPE"PLUMBING"
CDS_LIB"mstr_standard";
"B \NAC \NWC"5;
"S \NAC"
BN"8"33;
%"TAP"
"1","(-5550,2650)","2","mstr_standard","I29";
;
HDL_TAP"TRUE"
BODY_TYPE"PLUMBING"
CDS_LIB"mstr_standard";
"B \NAC \NWC"5;
"S \NAC"
BN"9"34;
%"TAP"
"1","(-5825,1950)","2","mstr_standard","I3";
;
HDL_TAP"TRUE"
BODY_TYPE"PLUMBING"
CDS_LIB"mstr_standard";
"B \NAC \NWC"8;
"S \NAC"
BN"2"12;
%"TAP"
"1","(-5550,2700)","2","mstr_standard","I30";
;
HDL_TAP"TRUE"
BODY_TYPE"PLUMBING"
CDS_LIB"mstr_standard";
"B \NAC \NWC"5;
"S \NAC"
BN"10"35;
%"TAP"
"1","(-5550,2750)","2","mstr_standard","I31";
;
HDL_TAP"TRUE"
BODY_TYPE"PLUMBING"
CDS_LIB"mstr_standard";
"B \NAC \NWC"5;
"S \NAC"
BN"11"36;
%"TAP"
"1","(-5550,3150)","2","mstr_standard","I32";
;
HDL_TAP"TRUE"
BODY_TYPE"PLUMBING"
CDS_LIB"mstr_standard";
"B \NAC \NWC"5;
"S \NAC"
BN"13"38;
%"TAP"
"1","(-5550,3100)","2","mstr_standard","I33";
;
HDL_TAP"TRUE"
BODY_TYPE"PLUMBING"
CDS_LIB"mstr_standard";
"B \NAC \NWC"5;
"S \NAC"
BN"12"37;
%"TAP"
"1","(-5550,3200)","2","mstr_standard","I34";
;
HDL_TAP"TRUE"
BODY_TYPE"PLUMBING"
CDS_LIB"mstr_standard";
"B \NAC \NWC"5;
"S \NAC"
BN"14"39;
%"TAP"
"1","(-5550,3250)","2","mstr_standard","I35";
;
HDL_TAP"TRUE"
BODY_TYPE"PLUMBING"
CDS_LIB"mstr_standard";
"B \NAC \NWC"5;
"S \NAC"
BN"15"40;
%"TAP"
"1","(-2625,1600)","0","mstr_standard","I36";
;
HDL_TAP"TRUE"
BODY_TYPE"PLUMBING"
CDS_LIB"mstr_standard";
"B \NAC \NWC"2;
"S \NAC"
BN"0"45;
%"TAP"
"1","(-2625,1650)","0","mstr_standard","I37";
;
HDL_TAP"TRUE"
BODY_TYPE"PLUMBING"
CDS_LIB"mstr_standard";
"B \NAC \NWC"2;
"S \NAC"
BN"1"46;
%"TAP"
"1","(-2625,1700)","0","mstr_standard","I38";
;
HDL_TAP"TRUE"
BODY_TYPE"PLUMBING"
CDS_LIB"mstr_standard";
"B \NAC \NWC"2;
"S \NAC"
BN"2"47;
%"TAP"
"1","(-2625,1750)","0","mstr_standard","I39";
;
HDL_TAP"TRUE"
BODY_TYPE"PLUMBING"
CDS_LIB"mstr_standard";
"B \NAC \NWC"2;
"S \NAC"
BN"3"48;
%"TAP"
"1","(-2175,1850)","0","mstr_standard","I40";
;
HDL_TAP"TRUE"
BODY_TYPE"PLUMBING"
CDS_LIB"mstr_standard";
"B \NAC \NWC"4;
"S \NAC"
BN"0"41;
%"TAP"
"1","(-2175,1900)","0","mstr_standard","I41";
;
HDL_TAP"TRUE"
BODY_TYPE"PLUMBING"
CDS_LIB"mstr_standard";
"B \NAC \NWC"4;
"S \NAC"
BN"1"42;
%"TAP"
"1","(-2175,1950)","0","mstr_standard","I42";
;
HDL_TAP"TRUE"
BODY_TYPE"PLUMBING"
CDS_LIB"mstr_standard";
"B \NAC \NWC"4;
"S \NAC"
BN"2"43;
%"TAP"
"1","(-2625,2100)","0","mstr_standard","I43";
;
HDL_TAP"TRUE"
BODY_TYPE"PLUMBING"
CDS_LIB"mstr_standard";
"B \NAC \NWC"2;
"S \NAC"
BN"4"61;
%"TAP"
"1","(-2625,2150)","0","mstr_standard","I44";
;
HDL_TAP"TRUE"
BODY_TYPE"PLUMBING"
CDS_LIB"mstr_standard";
"B \NAC \NWC"2;
"S \NAC"
BN"5"62;
%"TAP"
"1","(-2625,2200)","0","mstr_standard","I45";
;
HDL_TAP"TRUE"
BODY_TYPE"PLUMBING"
CDS_LIB"mstr_standard";
"B \NAC \NWC"2;
"S \NAC"
BN"6"63;
%"TAP"
"1","(-2625,2250)","0","mstr_standard","I46";
;
HDL_TAP"TRUE"
BODY_TYPE"PLUMBING"
CDS_LIB"mstr_standard";
"B \NAC \NWC"2;
"S \NAC"
BN"7"64;
%"TAP"
"1","(-2625,2600)","0","mstr_standard","I47";
;
HDL_TAP"TRUE"
BODY_TYPE"PLUMBING"
CDS_LIB"mstr_standard";
"B \NAC \NWC"1;
"S \NAC"
BN"8"65;
%"TAP"
"1","(-2625,2650)","0","mstr_standard","I48";
;
HDL_TAP"TRUE"
BODY_TYPE"PLUMBING"
CDS_LIB"mstr_standard";
"B \NAC \NWC"1;
"S \NAC"
BN"9"66;
%"TAP"
"1","(-2625,2700)","0","mstr_standard","I49";
;
HDL_TAP"TRUE"
BODY_TYPE"PLUMBING"
CDS_LIB"mstr_standard";
"B \NAC \NWC"1;
"S \NAC"
BN"10"67;
%"TAP"
"1","(-2175,2000)","0","mstr_standard","I51";
;
HDL_TAP"TRUE"
BODY_TYPE"PLUMBING"
CDS_LIB"mstr_standard";
"B \NAC \NWC"4;
"S \NAC"
BN"3"44;
%"TAP"
"1","(-2175,2350)","0","mstr_standard","I52";
;
HDL_TAP"TRUE"
BODY_TYPE"PLUMBING"
CDS_LIB"mstr_standard";
"B \NAC \NWC"4;
"S \NAC"
BN"4"49;
%"TAP"
"1","(-2175,2400)","0","mstr_standard","I53";
;
HDL_TAP"TRUE"
BODY_TYPE"PLUMBING"
CDS_LIB"mstr_standard";
"B \NAC \NWC"4;
"S \NAC"
BN"5"50;
%"TAP"
"1","(-2175,2450)","0","mstr_standard","I54";
;
HDL_TAP"TRUE"
BODY_TYPE"PLUMBING"
CDS_LIB"mstr_standard";
"B \NAC \NWC"4;
"S \NAC"
BN"6"51;
%"TAP"
"1","(-2175,2500)","0","mstr_standard","I55";
;
HDL_TAP"TRUE"
BODY_TYPE"PLUMBING"
CDS_LIB"mstr_standard";
"B \NAC \NWC"4;
"S \NAC"
BN"7"52;
%"TAP"
"1","(-2175,2850)","0","mstr_standard","I56";
;
HDL_TAP"TRUE"
BODY_TYPE"PLUMBING"
CDS_LIB"mstr_standard";
"B \NAC \NWC"3;
"S \NAC"
BN"8"53;
%"TAP"
"1","(-2175,2950)","0","mstr_standard","I57";
;
HDL_TAP"TRUE"
BODY_TYPE"PLUMBING"
CDS_LIB"mstr_standard";
"B \NAC \NWC"3;
"S \NAC"
BN"10"55;
%"TAP"
"1","(-2175,2900)","0","mstr_standard","I58";
;
HDL_TAP"TRUE"
BODY_TYPE"PLUMBING"
CDS_LIB"mstr_standard";
"B \NAC \NWC"3;
"S \NAC"
BN"9"54;
%"TAP"
"1","(-2625,3100)","0","mstr_standard","I59";
;
HDL_TAP"TRUE"
BODY_TYPE"PLUMBING"
CDS_LIB"mstr_standard";
"B \NAC \NWC"1;
"S \NAC"
BN"12"69;
%"TAP"
"1","(-5825,2000)","2","mstr_standard","I6";
;
HDL_TAP"TRUE"
BODY_TYPE"PLUMBING"
CDS_LIB"mstr_standard";
"B \NAC \NWC"8;
"S \NAC"
BN"3"13;
%"TAP"
"1","(-2625,3150)","0","mstr_standard","I60";
;
HDL_TAP"TRUE"
BODY_TYPE"PLUMBING"
CDS_LIB"mstr_standard";
"B \NAC \NWC"1;
"S \NAC"
BN"13"70;
%"TAP"
"1","(-2625,3250)","0","mstr_standard","I61";
;
HDL_TAP"TRUE"
BODY_TYPE"PLUMBING"
CDS_LIB"mstr_standard";
"B \NAC \NWC"1;
"S \NAC"
BN"15"72;
%"TAP"
"1","(-2625,3200)","0","mstr_standard","I62";
;
HDL_TAP"TRUE"
BODY_TYPE"PLUMBING"
CDS_LIB"mstr_standard";
"B \NAC \NWC"1;
"S \NAC"
BN"14"71;
%"TAP"
"1","(-2175,3350)","0","mstr_standard","I64";
;
HDL_TAP"TRUE"
BODY_TYPE"PLUMBING"
CDS_LIB"mstr_standard";
"B \NAC \NWC"3;
"S \NAC"
BN"12"57;
%"TAP"
"1","(-2175,3400)","0","mstr_standard","I65";
;
HDL_TAP"TRUE"
BODY_TYPE"PLUMBING"
CDS_LIB"mstr_standard";
"B \NAC \NWC"3;
"S \NAC"
BN"13"58;
%"TAP"
"1","(-2175,3500)","0","mstr_standard","I66";
;
HDL_TAP"TRUE"
BODY_TYPE"PLUMBING"
CDS_LIB"mstr_standard";
"B \NAC \NWC"3;
"S \NAC"
BN"15"60;
%"TAP"
"1","(-2175,3450)","0","mstr_standard","I67";
;
HDL_TAP"TRUE"
BODY_TYPE"PLUMBING"
CDS_LIB"mstr_standard";
"B \NAC \NWC"3;
"S \NAC"
BN"14"59;
%"TAP"
"1","(-5825,2350)","2","mstr_standard","I7";
;
HDL_TAP"TRUE"
BODY_TYPE"PLUMBING"
CDS_LIB"mstr_standard";
"B \NAC \NWC"8;
"S \NAC"
BN"4"17;
%"TAP"
"1","(-2175,3000)","0","mstr_standard","I78";
;
HDL_TAP"TRUE"
BODY_TYPE"PLUMBING"
CDS_LIB"mstr_standard";
"B \NAC \NWC"3;
"S \NAC"
BN"11"56;
%"TAP"
"1","(-2625,2750)","0","mstr_standard","I79";
;
HDL_TAP"TRUE"
BODY_TYPE"PLUMBING"
CDS_LIB"mstr_standard";
"B \NAC \NWC"1;
"S \NAC"
BN"11"68;
%"TAP"
"1","(-5825,2400)","2","mstr_standard","I8";
;
HDL_TAP"TRUE"
BODY_TYPE"PLUMBING"
CDS_LIB"mstr_standard";
"B \NAC \NWC"8;
"S \NAC"
BN"5"18;
%"SKX_EXT_B"
"10","(-4100,2550)","0","chpset_lib","I84";
;
CDS_SEC"10"
ROOM"CPU0"
CDS_LOCATION"U5D1"
SEC"10"
SEC_TYPE"BGA1"
CDS_LIB"chpset_lib"
PACK_TYPE"BGA1"
MATERIAL"IC"
PART_NUMBER"TBD"
LOCATION"U5D1";
"PE1_TX_DP<0>"
$PN"CW2"41;
"PE1_TX_DP<1>"
$PN"DB1"42;
"PE1_TX_DP<2>"
$PN"DD3"43;
"PE1_TX_DP<3>"
$PN"DC4"44;
"PE1_TX_DP<4>"
$PN"DF3"49;
"PE1_TX_DP<5>"
$PN"DH3"50;
"PE1_TX_DP<6>"
$PN"DL2"51;
"PE1_TX_DP<7>"
$PN"DP3"52;
"PE1_TX_DP<8>"
$PN"DR4"53;
"PE1_TX_DP<9>"
$PN"DU2"54;
"PE1_TX_DP<10>"
$PN"DU4"55;
"PE1_TX_DP<11>"
$PN"DV5"56;
"PE1_TX_DP<12>"
$PN"DT7"57;
"PE1_TX_DP<13>"
$PN"DW6"58;
"PE1_TX_DP<14>"
$PN"EB7"59;
"PE1_TX_DP<15>"
$PN"EC8"60;
"PE1_TX_DN<0>"
$PN"DA2"45;
"PE1_TX_DN<1>"
$PN"DC2"46;
"PE1_TX_DN<2>"
$PN"DE2"47;
"PE1_TX_DN<3>"
$PN"DE4"48;
"PE1_TX_DN<4>"
$PN"DG4"61;
"PE1_TX_DN<5>"
$PN"DK3"62;
"PE1_TX_DN<6>"
$PN"DM3"63;
"PE1_TX_DN<7>"
$PN"DN4"64;
"PE1_TX_DN<8>"
$PN"DT5"65;
"PE1_TX_DN<9>"
$PN"DV3"66;
"PE1_TX_DN<10>"
$PN"DW4"67;
"PE1_TX_DN<11>"
$PN"DU6"68;
"PE1_TX_DN<12>"
$PN"DV7"69;
"PE1_TX_DN<13>"
$PN"DY7"70;
"PE1_TX_DN<14>"
$PN"EA8"71;
"PE1_TX_DN<15>"
$PN"ED9"72;
"PE1_RX_DP<0>"
$PN"CU8"10;
"PE1_RX_DP<1>"
$PN"CY7"11;
"PE1_RX_DP<2>"
$PN"DB9"12;
"PE1_RX_DP<3>"
$PN"DA10"13;
"PE1_RX_DP<4>"
$PN"DD9"17;
"PE1_RX_DP<5>"
$PN"DF9"18;
"PE1_RX_DP<6>"
$PN"DJ8"19;
"PE1_RX_DP<7>"
$PN"DL10"20;
"PE1_RX_DP<8>"
$PN"DK11"21;
"PE1_RX_DP<9>"
$PN"DN10"22;
"PE1_RX_DP<10>"
$PN"DR12"23;
"PE1_RX_DP<11>"
$PN"DP13"24;
"PE1_RX_DP<12>"
$PN"DU12"25;
"PE1_RX_DP<13>"
$PN"DY13"26;
"PE1_RX_DP<14>"
$PN"DV15"27;
"PE1_RX_DP<15>"
$PN"DT15"28;
"PE1_RX_DN<0>"
$PN"CW8"14;
"PE1_RX_DN<1>"
$PN"DA8"15;
"PE1_RX_DN<2>"
$PN"DC8"16;
"PE1_RX_DN<3>"
$PN"DC10"9;
"PE1_RX_DN<4>"
$PN"DE10"29;
"PE1_RX_DN<5>"
$PN"DH9"30;
"PE1_RX_DN<6>"
$PN"DK9"31;
"PE1_RX_DN<7>"
$PN"DM9"32;
"PE1_RX_DN<8>"
$PN"DM11"33;
"PE1_RX_DN<9>"
$PN"DP11"34;
"PE1_RX_DN<10>"
$PN"DT11"35;
"PE1_RX_DN<11>"
$PN"DT13"36;
"PE1_RX_DN<12>"
$PN"DV13"37;
"PE1_RX_DN<13>"
$PN"DW14"38;
"PE1_RX_DN<14>"
$PN"DY15"39;
"PE1_RX_DN<15>"
$PN"DU16"40;
%"TAP"
"1","(-5825,2450)","2","mstr_standard","I9";
;
HDL_TAP"TRUE"
BODY_TYPE"PLUMBING"
CDS_LIB"mstr_standard";
"B \NAC \NWC"8;
"S \NAC"
BN"6"19;
END.
